(kicad_pcb
	(version 20260206)
	(generator "pcbnew")
	(generator_version "10.0")
	(general
		(thickness 1.6)
		(legacy_teardrops no)
	)
	(paper "A4")
	(title_block
		(title "04192023_DAF0TMB3IC0_F0TG_MB_C_brd_V02_OCP.brd")
		(comment 1 "Grand Teton / footprints 5813-5822 of 8354")
	)
	(layers
		(0 "F.Cu" signal "TOP")
		(4 "In1.Cu" signal "GND")
		(6 "In2.Cu" signal "IN1")
		(8 "In3.Cu" signal "GND1")
		(10 "In4.Cu" signal "IN2")
		(12 "In5.Cu" signal "GND2")
		(14 "In6.Cu" signal "IN3")
		(16 "In7.Cu" signal "GND3")
		(18 "In8.Cu" signal "VCC")
		(20 "In9.Cu" signal "VCC1")
		(22 "In10.Cu" signal "GND4")
		(24 "In11.Cu" signal "IN4")
		(26 "In12.Cu" signal "GND5")
		(28 "In13.Cu" signal "IN5")
		(30 "In14.Cu" signal "GND6")
		(32 "In15.Cu" signal "IN6")
		(34 "In16.Cu" signal "GND7")
		(2 "B.Cu" signal "BOTTOM")
		(9 "F.Adhes" user "F.Adhesive")
		(11 "B.Adhes" user "B.Adhesive")
		(13 "F.Paste" user "Package Geometry/Pastemask Top")
		(15 "B.Paste" user "Package Geometry/Pastemask Bottom")
		(5 "F.SilkS" user "Ref Des/Silkscreen Top")
		(7 "B.SilkS" user "Ref Des/Silkscreen Bottom")
		(1 "F.Mask" user "Board Geometry/Soldermask Top")
		(3 "B.Mask" user "Board Geometry/Soldermask Bottom")
		(17 "Dwgs.User" user "User.Drawings")
		(19 "Cmts.User" user "User.Comments")
		(21 "Eco1.User" user "User.Eco1")
		(23 "Eco2.User" user "User.Eco2")
		(25 "Edge.Cuts" user "Board Geometry/Outline")
		(27 "Margin" user)
		(31 "F.CrtYd" user "Package Geometry/Place Bound Top")
		(29 "B.CrtYd" user "Package Geometry/Place Bound Bottom")
		(35 "F.Fab" user "Ref Des/Assembly Top")
		(33 "B.Fab" user "Ref Des/Assembly Bottom")
	)
	(footprint ""
		(layer "B.Cu")
		(at 370.427758 -269.30731)
		(property "Reference" "C2228"
			(at 0 0 0)
			(layer "B.SilkS")
			(hide yes)
			(effects
				(font
					(size 1.27 1.27)
				)
				(justify mirror)
			)
		)
		(property "Value" ""
			(at 0 0 0)
			(layer "B.Fab")
			(effects
				(font
					(size 1.27 1.27)
				)
				(justify mirror)
			)
		)
		(duplicate_pad_numbers_are_jumpers no)
		(fp_line
			(start -0.7874 -0.4064)
			(end -0.7874 0.4064)
			(stroke
				(width 0.1524)
				(type default)
			)
			(layer "B.SilkS")
		)
		(fp_line
			(start -0.7874 0.4064)
			(end 0.7874 0.4064)
			(stroke
				(width 0.1524)
				(type default)
			)
			(layer "B.SilkS")
		)
		(fp_line
			(start 0.7874 -0.4064)
			(end -0.7874 -0.4064)
			(stroke
				(width 0.1524)
				(type default)
			)
			(layer "B.SilkS")
		)
		(fp_line
			(start 0.7874 0.4064)
			(end 0.7874 -0.4064)
			(stroke
				(width 0.1524)
				(type default)
			)
			(layer "B.SilkS")
		)
		(fp_line
			(start -0.67945 -0.3048)
			(end -0.67945 0.3048)
			(stroke
				(width 0.1)
				(type default)
			)
			(layer "B.Fab")
		)
		(fp_line
			(start -0.67945 0.3048)
			(end -0.120396 0.3048)
			(stroke
				(width 0.1)
				(type default)
			)
			(layer "B.Fab")
		)
		(fp_line
			(start -0.12065 -0.3048)
			(end -0.67945 -0.3048)
			(stroke
				(width 0.1)
				(type default)
			)
			(layer "B.Fab")
		)
		(fp_line
			(start -0.12065 -0.2794)
			(end -0.12065 -0.3048)
			(stroke
				(width 0.1)
				(type default)
			)
			(layer "B.Fab")
		)
		(fp_line
			(start -0.120396 0.2794)
			(end 0.12065 0.2794)
			(stroke
				(width 0.1)
				(type default)
			)
			(layer "B.Fab")
		)
		(fp_line
			(start -0.120396 0.3048)
			(end -0.120396 0.2794)
			(stroke
				(width 0.1)
				(type default)
			)
			(layer "B.Fab")
		)
		(fp_line
			(start 0.12065 -0.305054)
			(end 0.12065 -0.2794)
			(stroke
				(width 0.1)
				(type default)
			)
			(layer "B.Fab")
		)
		(fp_line
			(start 0.12065 -0.2794)
			(end -0.12065 -0.2794)
			(stroke
				(width 0.1)
				(type default)
			)
			(layer "B.Fab")
		)
		(fp_line
			(start 0.12065 0.2794)
			(end 0.12065 0.3048)
			(stroke
				(width 0.1)
				(type default)
			)
			(layer "B.Fab")
		)
		(fp_line
			(start 0.12065 0.3048)
			(end 0.67945 0.3048)
			(stroke
				(width 0.1)
				(type default)
			)
			(layer "B.Fab")
		)
		(fp_line
			(start 0.67945 -0.305054)
			(end 0.12065 -0.305054)
			(stroke
				(width 0.1)
				(type default)
			)
			(layer "B.Fab")
		)
		(fp_line
			(start 0.67945 0.3048)
			(end 0.67945 -0.305054)
			(stroke
				(width 0.1)
				(type default)
			)
			(layer "B.Fab")
		)
		(pad "1" smd circle
			(at 0.40005 0 180)
			(size 0 0)
			(layers "B.Cu" "B.Mask" "B.Paste")
			(net "PVDDCR_CPU1_P0")
		)
		(pad "2" smd circle
			(at -0.40005 0 180)
			(size 0 0)
			(layers "B.Cu" "B.Mask" "B.Paste")
			(net "GND")
		)
	)
	(footprint ""
		(layer "B.Cu")
		(at 306.214526 -416.899344 90)
		(property "Reference" "C6533"
			(at 0 0 90)
			(layer "B.SilkS")
			(hide yes)
			(effects
				(font
					(size 1.27 1.27)
				)
				(justify mirror)
			)
		)
		(property "Value" ""
			(at 0 0 90)
			(layer "B.Fab")
			(effects
				(font
					(size 1.27 1.27)
				)
				(justify mirror)
			)
		)
		(duplicate_pad_numbers_are_jumpers no)
		(fp_line
			(start 0.299974 -0.150114)
			(end -0.299974 -0.150114)
			(stroke
				(width 0.1)
				(type default)
			)
			(layer "B.Fab")
		)
		(fp_line
			(start -0.299974 -0.150114)
			(end -0.299974 0.150114)
			(stroke
				(width 0.1)
				(type default)
			)
			(layer "B.Fab")
		)
		(fp_line
			(start 0.299974 0.150114)
			(end 0.299974 -0.150114)
			(stroke
				(width 0.1)
				(type default)
			)
			(layer "B.Fab")
		)
		(fp_line
			(start -0.299974 0.150114)
			(end 0.299974 0.150114)
			(stroke
				(width 0.1)
				(type default)
			)
			(layer "B.Fab")
		)
		(pad "1" smd rect
			(at 0.2667 0 270)
			(size 0.3048 0.381)
			(layers "B.Cu" "B.Mask" "B.Paste")
			(net "P5E_CPU0_P1_TX_BUF_C_DP<0>")
		)
		(pad "2" smd rect
			(at -0.2667 0 270)
			(size 0.3048 0.381)
			(layers "B.Cu" "B.Mask" "B.Paste")
			(net "P5E_CPU0_P1_TX_BUF_DP<0>")
		)
	)
	(footprint ""
		(layer "B.Cu")
		(at 424.783758 -391.686288 180)
		(property "Reference" "R1083"
			(at 0 0 0)
			(layer "B.SilkS")
			(hide yes)
			(effects
				(font
					(size 1.27 1.27)
				)
				(justify mirror)
			)
		)
		(property "Value" ""
			(at 0 0 0)
			(layer "B.Fab")
			(effects
				(font
					(size 1.27 1.27)
				)
				(justify mirror)
			)
		)
		(duplicate_pad_numbers_are_jumpers no)
		(fp_line
			(start 0.32512 0.175006)
			(end 0.32512 -0.175006)
			(stroke
				(width 0.1)
				(type default)
			)
			(layer "B.Fab")
		)
		(fp_line
			(start 0.32512 -0.175006)
			(end -0.32512 -0.175006)
			(stroke
				(width 0.1)
				(type default)
			)
			(layer "B.Fab")
		)
		(fp_line
			(start -0.32512 0.175006)
			(end 0.32512 0.175006)
			(stroke
				(width 0.1)
				(type default)
			)
			(layer "B.Fab")
		)
		(fp_line
			(start -0.32512 -0.175006)
			(end -0.32512 0.175006)
			(stroke
				(width 0.1)
				(type default)
			)
			(layer "B.Fab")
		)
		(pad "1" smd rect
			(at 0.2667 0)
			(size 0.3048 0.381)
			(layers "B.Cu" "B.Mask" "B.Paste")
			(net "NCF_CPU0_P2_GND")
		)
		(pad "2" smd rect
			(at -0.2667 0 180)
			(size 0.3048 0.381)
			(layers "B.Cu" "B.Mask" "B.Paste")
			(net "GND")
		)
	)
	(footprint ""
		(layer "B.Cu")
		(at 339.566758 -214.880952 90)
		(property "Reference" "R435"
			(at 0 0 90)
			(layer "B.SilkS")
			(hide yes)
			(effects
				(font
					(size 1.27 1.27)
				)
				(justify mirror)
			)
		)
		(property "Value" ""
			(at 0 0 90)
			(layer "B.Fab")
			(effects
				(font
					(size 1.27 1.27)
				)
				(justify mirror)
			)
		)
		(duplicate_pad_numbers_are_jumpers no)
		(fp_line
			(start 0.384048 -0.4064)
			(end -0.377952 -0.4064)
			(stroke
				(width 0.1524)
				(type default)
			)
			(layer "B.SilkS")
		)
		(fp_line
			(start -0.7874 0.132842)
			(end -0.7874 0.4064)
			(stroke
				(width 0.1524)
				(type default)
			)
			(layer "B.SilkS")
		)
		(fp_line
			(start 0.7874 0.4064)
			(end 0.7874 0.005842)
			(stroke
				(width 0.1524)
				(type default)
			)
			(layer "B.SilkS")
		)
		(fp_line
			(start -0.7874 0.4064)
			(end 0.7874 0.4064)
			(stroke
				(width 0.1524)
				(type default)
			)
			(layer "B.SilkS")
		)
		(fp_line
			(start 0.67945 -0.305054)
			(end 0.12065 -0.305054)
			(stroke
				(width 0.1)
				(type default)
			)
			(layer "B.Fab")
		)
		(fp_line
			(start 0.12065 -0.305054)
			(end 0.12065 -0.2794)
			(stroke
				(width 0.1)
				(type default)
			)
			(layer "B.Fab")
		)
		(fp_line
			(start -0.12065 -0.3048)
			(end -0.67945 -0.3048)
			(stroke
				(width 0.1)
				(type default)
			)
			(layer "B.Fab")
		)
		(fp_line
			(start -0.67945 -0.3048)
			(end -0.67945 0.3048)
			(stroke
				(width 0.1)
				(type default)
			)
			(layer "B.Fab")
		)
		(fp_line
			(start 0.12065 -0.2794)
			(end -0.12065 -0.2794)
			(stroke
				(width 0.1)
				(type default)
			)
			(layer "B.Fab")
		)
		(fp_line
			(start -0.12065 -0.2794)
			(end -0.12065 -0.3048)
			(stroke
				(width 0.1)
				(type default)
			)
			(layer "B.Fab")
		)
		(fp_line
			(start 0.12065 0.2794)
			(end 0.12065 0.3048)
			(stroke
				(width 0.1)
				(type default)
			)
			(layer "B.Fab")
		)
		(fp_line
			(start -0.120396 0.2794)
			(end 0.12065 0.2794)
			(stroke
				(width 0.1)
				(type default)
			)
			(layer "B.Fab")
		)
		(fp_line
			(start 0.67945 0.3048)
			(end 0.67945 -0.305054)
			(stroke
				(width 0.1)
				(type default)
			)
			(layer "B.Fab")
		)
		(fp_line
			(start 0.12065 0.3048)
			(end 0.67945 0.3048)
			(stroke
				(width 0.1)
				(type default)
			)
			(layer "B.Fab")
		)
		(fp_line
			(start -0.120396 0.3048)
			(end -0.120396 0.2794)
			(stroke
				(width 0.1)
				(type default)
			)
			(layer "B.Fab")
		)
		(fp_line
			(start -0.67945 0.3048)
			(end -0.120396 0.3048)
			(stroke
				(width 0.1)
				(type default)
			)
			(layer "B.Fab")
		)
		(pad "1" smd circle
			(at 0.40005 0 270)
			(size 0 0)
			(layers "B.Cu" "B.Mask" "B.Paste")
			(net "CLK_100M_REF_OUT_DP")
		)
		(pad "2" smd circle
			(at -0.40005 0 270)
			(size 0 0)
			(layers "B.Cu" "B.Mask" "B.Paste")
			(net "CLK_100M_REF_IN_DP")
		)
	)
	(footprint ""
		(layer "B.Cu")
		(at 126.618492 -388.011162 -90)
		(property "Reference" "C458"
			(at 0 0 90)
			(layer "B.SilkS")
			(hide yes)
			(effects
				(font
					(size 1.27 1.27)
				)
				(justify mirror)
			)
		)
		(property "Value" ""
			(at 0 0 90)
			(layer "B.Fab")
			(effects
				(font
					(size 1.27 1.27)
				)
				(justify mirror)
			)
		)
		(duplicate_pad_numbers_are_jumpers no)
		(fp_line
			(start -0.299974 0.150114)
			(end 0.299974 0.150114)
			(stroke
				(width 0.1)
				(type default)
			)
			(layer "B.Fab")
		)
		(fp_line
			(start 0.299974 0.150114)
			(end 0.299974 -0.150114)
			(stroke
				(width 0.1)
				(type default)
			)
			(layer "B.Fab")
		)
		(fp_line
			(start -0.299974 -0.150114)
			(end -0.299974 0.150114)
			(stroke
				(width 0.1)
				(type default)
			)
			(layer "B.Fab")
		)
		(fp_line
			(start 0.299974 -0.150114)
			(end -0.299974 -0.150114)
			(stroke
				(width 0.1)
				(type default)
			)
			(layer "B.Fab")
		)
		(pad "1" smd rect
			(at 0.2667 0 90)
			(size 0.3048 0.381)
			(layers "B.Cu" "B.Mask" "B.Paste")
			(net "P0V9_CPU1_RT_2D")
		)
		(pad "2" smd rect
			(at -0.2667 0 90)
			(size 0.3048 0.381)
			(layers "B.Cu" "B.Mask" "B.Paste")
			(net "GND")
		)
	)
	(footprint ""
		(layer "B.Cu")
		(at 98.60534 -254.956564)
		(property "Reference" "C2661"
			(at 0 0 0)
			(layer "B.SilkS")
			(hide yes)
			(effects
				(font
					(size 1.27 1.27)
				)
				(justify mirror)
			)
		)
		(property "Value" ""
			(at 0 0 0)
			(layer "B.Fab")
			(effects
				(font
					(size 1.27 1.27)
				)
				(justify mirror)
			)
		)
		(duplicate_pad_numbers_are_jumpers no)
		(fp_line
			(start -0.7874 -0.4064)
			(end -0.7874 0.4064)
			(stroke
				(width 0.1524)
				(type default)
			)
			(layer "B.SilkS")
		)
		(fp_line
			(start -0.7874 0.4064)
			(end 0.7874 0.4064)
			(stroke
				(width 0.1524)
				(type default)
			)
			(layer "B.SilkS")
		)
		(fp_line
			(start 0.7874 -0.4064)
			(end -0.7874 -0.4064)
			(stroke
				(width 0.1524)
				(type default)
			)
			(layer "B.SilkS")
		)
		(fp_line
			(start 0.7874 0.4064)
			(end 0.7874 -0.4064)
			(stroke
				(width 0.1524)
				(type default)
			)
			(layer "B.SilkS")
		)
		(fp_line
			(start -0.67945 -0.3048)
			(end -0.67945 0.3048)
			(stroke
				(width 0.1)
				(type default)
			)
			(layer "B.Fab")
		)
		(fp_line
			(start -0.67945 0.3048)
			(end -0.120396 0.3048)
			(stroke
				(width 0.1)
				(type default)
			)
			(layer "B.Fab")
		)
		(fp_line
			(start -0.12065 -0.3048)
			(end -0.67945 -0.3048)
			(stroke
				(width 0.1)
				(type default)
			)
			(layer "B.Fab")
		)
		(fp_line
			(start -0.12065 -0.2794)
			(end -0.12065 -0.3048)
			(stroke
				(width 0.1)
				(type default)
			)
			(layer "B.Fab")
		)
		(fp_line
			(start -0.120396 0.2794)
			(end 0.12065 0.2794)
			(stroke
				(width 0.1)
				(type default)
			)
			(layer "B.Fab")
		)
		(fp_line
			(start -0.120396 0.3048)
			(end -0.120396 0.2794)
			(stroke
				(width 0.1)
				(type default)
			)
			(layer "B.Fab")
		)
		(fp_line
			(start 0.12065 -0.305054)
			(end 0.12065 -0.2794)
			(stroke
				(width 0.1)
				(type default)
			)
			(layer "B.Fab")
		)
		(fp_line
			(start 0.12065 -0.2794)
			(end -0.12065 -0.2794)
			(stroke
				(width 0.1)
				(type default)
			)
			(layer "B.Fab")
		)
		(fp_line
			(start 0.12065 0.2794)
			(end 0.12065 0.3048)
			(stroke
				(width 0.1)
				(type default)
			)
			(layer "B.Fab")
		)
		(fp_line
			(start 0.12065 0.3048)
			(end 0.67945 0.3048)
			(stroke
				(width 0.1)
				(type default)
			)
			(layer "B.Fab")
		)
		(fp_line
			(start 0.67945 -0.305054)
			(end 0.12065 -0.305054)
			(stroke
				(width 0.1)
				(type default)
			)
			(layer "B.Fab")
		)
		(fp_line
			(start 0.67945 0.3048)
			(end 0.67945 -0.305054)
			(stroke
				(width 0.1)
				(type default)
			)
			(layer "B.Fab")
		)
		(pad "1" smd circle
			(at 0.40005 0 180)
			(size 0 0)
			(layers "B.Cu" "B.Mask" "B.Paste")
			(net "PVDD18_S5_P1")
		)
		(pad "2" smd circle
			(at -0.40005 0 180)
			(size 0 0)
			(layers "B.Cu" "B.Mask" "B.Paste")
			(net "GND")
		)
	)
	(footprint ""
		(layer "B.Cu")
		(at 121.678446 -386.766562 90)
		(property "Reference" "C446"
			(at 0 0 90)
			(layer "B.SilkS")
			(hide yes)
			(effects
				(font
					(size 1.27 1.27)
				)
				(justify mirror)
			)
		)
		(property "Value" ""
			(at 0 0 90)
			(layer "B.Fab")
			(effects
				(font
					(size 1.27 1.27)
				)
				(justify mirror)
			)
		)
		(duplicate_pad_numbers_are_jumpers no)
		(fp_line
			(start 0.299974 -0.150114)
			(end -0.299974 -0.150114)
			(stroke
				(width 0.1)
				(type default)
			)
			(layer "B.Fab")
		)
		(fp_line
			(start -0.299974 -0.150114)
			(end -0.299974 0.150114)
			(stroke
				(width 0.1)
				(type default)
			)
			(layer "B.Fab")
		)
		(fp_line
			(start 0.299974 0.150114)
			(end 0.299974 -0.150114)
			(stroke
				(width 0.1)
				(type default)
			)
			(layer "B.Fab")
		)
		(fp_line
			(start -0.299974 0.150114)
			(end 0.299974 0.150114)
			(stroke
				(width 0.1)
				(type default)
			)
			(layer "B.Fab")
		)
		(pad "1" smd rect
			(at 0.2667 0 270)
			(size 0.3048 0.381)
			(layers "B.Cu" "B.Mask" "B.Paste")
			(net "P1V8_CPU1_RT3_1A")
		)
		(pad "2" smd rect
			(at -0.2667 0 270)
			(size 0.3048 0.381)
			(layers "B.Cu" "B.Mask" "B.Paste")
			(net "GND")
		)
	)
	(footprint ""
		(layer "B.Cu")
		(at 335.618836 -151.069294 90)
		(property "Reference" "PC260"
			(at 0 0 90)
			(layer "B.SilkS")
			(hide yes)
			(effects
				(font
					(size 1.27 1.27)
				)
				(justify mirror)
			)
		)
		(property "Value" ""
			(at 0 0 90)
			(layer "B.Fab")
			(effects
				(font
					(size 1.27 1.27)
				)
				(justify mirror)
			)
		)
		(duplicate_pad_numbers_are_jumpers no)
		(fp_line
			(start 1.524 -0.762)
			(end -1.524 -0.762)
			(stroke
				(width 0.1524)
				(type default)
			)
			(layer "B.SilkS")
		)
		(fp_line
			(start -1.524 -0.762)
			(end -1.524 0.762)
			(stroke
				(width 0.1524)
				(type default)
			)
			(layer "B.SilkS")
		)
		(fp_line
			(start 1.524 0.762)
			(end 1.524 -0.762)
			(stroke
				(width 0.1524)
				(type default)
			)
			(layer "B.SilkS")
		)
		(fp_line
			(start -1.524 0.762)
			(end 1.524 0.762)
			(stroke
				(width 0.1524)
				(type default)
			)
			(layer "B.SilkS")
		)
		(fp_line
			(start 1.1049 -0.724916)
			(end 1.1049 0.724916)
			(stroke
				(width 0.1)
				(type default)
			)
			(layer "B.Fab")
		)
		(fp_line
			(start -1.1049 -0.724916)
			(end 1.1049 -0.724916)
			(stroke
				(width 0.1)
				(type default)
			)
			(layer "B.Fab")
		)
		(fp_line
			(start 1.1049 0.724916)
			(end -1.1049 0.724916)
			(stroke
				(width 0.1)
				(type default)
			)
			(layer "B.Fab")
		)
		(fp_line
			(start -1.1049 0.724916)
			(end -1.1049 -0.724916)
			(stroke
				(width 0.1)
				(type default)
			)
			(layer "B.Fab")
		)
		(pad "1" smd rect
			(at 0.889 0 90)
			(size 1.016 1.27)
			(layers "B.Cu" "B.Mask" "B.Paste")
			(net "PVDD18_S5_P0")
		)
		(pad "2" smd rect
			(at -0.889 0 90)
			(size 1.016 1.27)
			(layers "B.Cu" "B.Mask" "B.Paste")
			(net "GND")
		)
	)
	(footprint ""
		(layer "B.Cu")
		(at 451.577456 -52.849526 -90)
		(property "Reference" "PC8071"
			(at 0 0 90)
			(layer "B.SilkS")
			(hide yes)
			(effects
				(font
					(size 1.27 1.27)
				)
				(justify mirror)
			)
		)
		(property "Value" ""
			(at 0 0 90)
			(layer "B.Fab")
			(effects
				(font
					(size 1.27 1.27)
				)
				(justify mirror)
			)
		)
		(duplicate_pad_numbers_are_jumpers no)
		(fp_line
			(start -1.524 0.762)
			(end 1.524 0.762)
			(stroke
				(width 0.1524)
				(type default)
			)
			(layer "B.SilkS")
		)
		(fp_line
			(start 1.524 0.762)
			(end 1.524 -0.762)
			(stroke
				(width 0.1524)
				(type default)
			)
			(layer "B.SilkS")
		)
		(fp_line
			(start -1.524 -0.762)
			(end -1.524 0.762)
			(stroke
				(width 0.1524)
				(type default)
			)
			(layer "B.SilkS")
		)
		(fp_line
			(start 1.524 -0.762)
			(end -1.524 -0.762)
			(stroke
				(width 0.1524)
				(type default)
			)
			(layer "B.SilkS")
		)
		(fp_line
			(start -1.1049 0.724916)
			(end -1.1049 -0.724916)
			(stroke
				(width 0.1)
				(type default)
			)
			(layer "B.Fab")
		)
		(fp_line
			(start 1.1049 0.724916)
			(end -1.1049 0.724916)
			(stroke
				(width 0.1)
				(type default)
			)
			(layer "B.Fab")
		)
		(fp_line
			(start -1.1049 -0.724916)
			(end 1.1049 -0.724916)
			(stroke
				(width 0.1)
				(type default)
			)
			(layer "B.Fab")
		)
		(fp_line
			(start 1.1049 -0.724916)
			(end 1.1049 0.724916)
			(stroke
				(width 0.1)
				(type default)
			)
			(layer "B.Fab")
		)
		(pad "1" smd rect
			(at 0.889 0 270)
			(size 1.016 1.27)
			(layers "B.Cu" "B.Mask" "B.Paste")
			(net "SW_P3V3_AUX_FLT")
		)
		(pad "2" smd rect
			(at -0.889 0 270)
			(size 1.016 1.27)
			(layers "B.Cu" "B.Mask" "B.Paste")
			(net "GND")
		)
	)
	(footprint ""
		(layer "B.Cu")
		(at 398.893538 -393.96416 180)
		(property "Reference" "R1074"
			(at 0 0 0)
			(layer "B.SilkS")
			(hide yes)
			(effects
				(font
					(size 1.27 1.27)
				)
				(justify mirror)
			)
		)
		(property "Value" ""
			(at 0 0 0)
			(layer "B.Fab")
			(effects
				(font
					(size 1.27 1.27)
				)
				(justify mirror)
			)
		)
		(duplicate_pad_numbers_are_jumpers no)
		(fp_line
			(start 0.32512 0.175006)
			(end 0.32512 -0.175006)
			(stroke
				(width 0.1)
				(type default)
			)
			(layer "B.Fab")
		)
		(fp_line
			(start 0.32512 -0.175006)
			(end -0.32512 -0.175006)
			(stroke
				(width 0.1)
				(type default)
			)
			(layer "B.Fab")
		)
		(fp_line
			(start -0.32512 0.175006)
			(end 0.32512 0.175006)
			(stroke
				(width 0.1)
				(type default)
			)
			(layer "B.Fab")
		)
		(fp_line
			(start -0.32512 -0.175006)
			(end -0.32512 0.175006)
			(stroke
				(width 0.1)
				(type default)
			)
			(layer "B.Fab")
		)
		(pad "1" smd rect
			(at 0.2667 0)
			(size 0.3048 0.381)
			(layers "B.Cu" "B.Mask" "B.Paste")
			(net "TEST0_RT_CPU0_P2")
		)
		(pad "2" smd rect
			(at -0.2667 0 180)
			(size 0.3048 0.381)
			(layers "B.Cu" "B.Mask" "B.Paste")
			(net "GND")
		)
	)
)
